(kicad_pcb
	(version 20260206)
	(generator "pcbnew")
	(generator_version "10.0")
	(general
		(thickness 1.6)
		(legacy_teardrops no)
	)
	(paper "A4")
	(title_block
		(title "Bryce Canyon_IOM_IOC_16318-2_OCP.brd")
		(comment 1 "Bryce Canyon / footprints 242-249 of 1605")
	)
	(layers
		(0 "F.Cu" signal "TOP")
		(4 "In1.Cu" signal "L2GND")
		(6 "In2.Cu" signal "L3")
		(8 "In3.Cu" signal "L4VCC")
		(10 "In4.Cu" signal "L5VCC")
		(12 "In5.Cu" signal "L6")
		(14 "In6.Cu" signal "L7GND")
		(2 "B.Cu" signal "BOTTOM")
		(9 "F.Adhes" user "F.Adhesive")
		(11 "B.Adhes" user "B.Adhesive")
		(13 "F.Paste" user "Package Geometry/Pastemask Top")
		(15 "B.Paste" user "Package Geometry/Pastemask Bottom")
		(5 "F.SilkS" user "Ref Des/Silkscreen Top")
		(7 "B.SilkS" user "Ref Des/Silkscreen Bottom")
		(1 "F.Mask" user "Board Geometry/Soldermask Top")
		(3 "B.Mask" user "Board Geometry/Soldermask Bottom")
		(17 "Dwgs.User" user "User.Drawings")
		(19 "Cmts.User" user "User.Comments")
		(21 "Eco1.User" user "User.Eco1")
		(23 "Eco2.User" user "User.Eco2")
		(25 "Edge.Cuts" user "Board Geometry/Outline")
		(27 "Margin" user)
		(31 "F.CrtYd" user "Package Geometry/Place Bound Top")
		(29 "B.CrtYd" user "Package Geometry/Place Bound Bottom")
		(35 "F.Fab" user "Ref Des/Assembly Top")
		(33 "B.Fab" user "Ref Des/Assembly Bottom")
	)
	(footprint ""
		(layer "F.Cu")
		(at 51.906678 -166.417244 180)
		(property "Reference" "R777"
			(at 0 0 180)
			(layer "F.SilkS")
			(hide yes)
			(effects
				(font
					(size 1.27 1.27)
				)
			)
		)
		(property "Value" "1KR2F-3-GP"
			(at 0.064008 -3.993896 180)
			(unlocked yes)
			(layer "F.Fab")
			(hide yes)
			(effects
				(font
					(size 1.016 1.016)
					(thickness 0.1524)
				)
			)
		)
		(property "Device Type" "R402H16"
			(at 0.064008 -5.517896 180)
			(unlocked yes)
			(layer "F.Fab")
			(hide yes)
			(effects
				(font
					(size 1.016 1.016)
					(thickness 0.1524)
				)
			)
		)
		(duplicate_pad_numbers_are_jumpers no)
		(fp_line
			(start 0.508 -0.9398)
			(end -0.508 -0.9398)
			(stroke
				(width 0.1524)
				(type default)
			)
			(layer "F.SilkS")
		)
		(fp_line
			(start -0.508 -0.9398)
			(end -0.508 0.9398)
			(stroke
				(width 0.1524)
				(type default)
			)
			(layer "F.SilkS")
		)
		(fp_rect
			(start -0.508 0.9398)
			(end 0.508 -0.9398)
			(stroke
				(width 0)
				(type default)
			)
			(fill no)
			(layer "F.CrtYd")
		)
		(fp_rect
			(start -0.508 0.9398)
			(end 0.508 -0.9398)
			(stroke
				(width 0)
				(type default)
			)
			(fill no)
			(layer "F.Fab")
		)
		(pad "1" smd custom
			(at 0 -0.4445 180)
			(size 0.1397 0.1397)
			(layers "F.Cu" "F.Mask" "F.Paste")
			(net "ADC_P1V2_STBY")
			(options
				(clearance outline)
				(anchor circle)
			)
			(primitives
				(gr_poly
					(pts
						(arc
							(start -0.1778 -0.2794)
							(mid -0.249642 -0.249642)
							(end -0.2794 -0.1778)
						)
						(arc
							(start -0.2794 0.1778)
							(mid -0.249642 0.249642)
							(end -0.1778 0.2794)
						)
						(arc
							(start 0.1778 0.2794)
							(mid 0.249642 0.249642)
							(end 0.2794 0.1778)
						)
						(arc
							(start 0.2794 -0.1778)
							(mid 0.249642 -0.249642)
							(end 0.1778 -0.2794)
						)
					)
					(width 0)
					(fill yes)
				)
			)
		)
		(pad "2" smd custom
			(at 0 0.4445 180)
			(size 0.1397 0.1397)
			(layers "F.Cu" "F.Mask" "F.Paste")
			(net "GND")
			(options
				(clearance outline)
				(anchor circle)
			)
			(primitives
				(gr_poly
					(pts
						(arc
							(start -0.1778 -0.2794)
							(mid -0.249642 -0.249642)
							(end -0.2794 -0.1778)
						)
						(arc
							(start -0.2794 0.1778)
							(mid -0.249642 0.249642)
							(end -0.1778 0.2794)
						)
						(arc
							(start 0.1778 0.2794)
							(mid 0.249642 0.249642)
							(end 0.2794 0.1778)
						)
						(arc
							(start 0.2794 -0.1778)
							(mid 0.249642 -0.249642)
							(end 0.1778 -0.2794)
						)
					)
					(width 0)
					(fill yes)
				)
			)
		)
	)
	(footprint ""
		(layer "F.Cu")
		(at 78.905608 -138.01598 -90)
		(property "Reference" "U19"
			(at 0 0 270)
			(layer "F.SilkS")
			(hide yes)
			(effects
				(font
					(size 1.27 1.27)
				)
			)
		)
		(property "Value" "SN74LVC1G74DCUT-GP"
			(at 0 -11.1252 270)
			(unlocked yes)
			(layer "F.Fab")
			(hide yes)
			(effects
				(font
					(size 1.016 1.016)
					(thickness 0.1524)
				)
			)
		)
		(property "Device Type" "SSOIC8-4H36"
			(at 0 -12.6492 270)
			(unlocked yes)
			(layer "F.Fab")
			(hide yes)
			(effects
				(font
					(size 1.016 1.016)
					(thickness 0.1524)
				)
			)
		)
		(duplicate_pad_numbers_are_jumpers no)
		(fp_line
			(start -1.2573 2.1844)
			(end -1.2573 -2.1844)
			(stroke
				(width 0.1524)
				(type default)
			)
			(layer "F.SilkS")
		)
		(fp_line
			(start 1.2573 2.1844)
			(end -1.2573 2.1844)
			(stroke
				(width 0.1524)
				(type default)
			)
			(layer "F.SilkS")
		)
		(fp_line
			(start -1.2954 0.4572)
			(end -1.2954 2.159)
			(stroke
				(width 0.4064)
				(type default)
			)
			(layer "F.SilkS")
		)
		(fp_line
			(start -1.2065 0.2667)
			(end -1.27 0.2667)
			(stroke
				(width 0.1524)
				(type default)
			)
			(layer "F.SilkS")
		)
		(fp_line
			(start -0.9017 -0.0381)
			(end -1.2065 0.2667)
			(stroke
				(width 0.1524)
				(type default)
			)
			(layer "F.SilkS")
		)
		(fp_line
			(start -1.2573 -0.3556)
			(end -1.2192 -0.3556)
			(stroke
				(width 0.1524)
				(type default)
			)
			(layer "F.SilkS")
		)
		(fp_line
			(start -1.2192 -0.3556)
			(end -0.9017 -0.0381)
			(stroke
				(width 0.1524)
				(type default)
			)
			(layer "F.SilkS")
		)
		(fp_line
			(start -1.2573 -2.1844)
			(end 1.2573 -2.1844)
			(stroke
				(width 0.1524)
				(type default)
			)
			(layer "F.SilkS")
		)
		(fp_line
			(start 1.2573 -2.1844)
			(end 1.2573 2.1844)
			(stroke
				(width 0.1524)
				(type default)
			)
			(layer "F.SilkS")
		)
		(fp_poly
			(pts
				(xy -1.5113 2.4384) (xy 1.5113 2.4384) (xy 1.5113 -2.4384) (xy -1.5113 -2.4384)
			)
			(stroke
				(width 0)
				(type default)
			)
			(fill no)
			(layer "F.CrtYd")
		)
		(fp_poly
			(pts
				(xy -1.5113 -2.4384) (xy 1.5113 -2.4384) (xy 1.5113 2.4384) (xy -1.5113 2.4384)
			)
			(stroke
				(width 0)
				(type default)
			)
			(fill no)
			(layer "F.Fab")
		)
		(pad "1" smd rect
			(at -0.75057 1.1684 270)
			(size 0.3048 1.524)
			(layers "F.Cu" "F.Mask" "F.Paste")
			(net "DEBUG_HDR_UART_SEL")
		)
		(pad "2" smd rect
			(at -0.25019 1.1684 270)
			(size 0.3048 1.524)
			(layers "F.Cu" "F.Mask" "F.Paste")
			(net "D_FLIP_D")
		)
		(pad "3" smd rect
			(at 0.25019 1.1684 270)
			(size 0.3048 1.524)
			(layers "F.Cu" "F.Mask" "F.Paste")
			(net "D_FLIP_Q#")
		)
		(pad "4" smd rect
			(at 0.75057 1.1684 270)
			(size 0.3048 1.524)
			(layers "F.Cu" "F.Mask" "F.Paste")
			(net "GND")
		)
		(pad "5" smd rect
			(at 0.75057 -1.1684 270)
			(size 0.3048 1.524)
			(layers "F.Cu" "F.Mask" "F.Paste")
			(net "D_FLIP_Q")
		)
		(pad "6" smd rect
			(at 0.25019 -1.1684 270)
			(size 0.3048 1.524)
			(layers "F.Cu" "F.Mask" "F.Paste")
			(net "D_FLIP_CLR#")
		)
		(pad "7" smd rect
			(at -0.25019 -1.1684 270)
			(size 0.3048 1.524)
			(layers "F.Cu" "F.Mask" "F.Paste")
			(net "D_FLIP_PRE#")
		)
		(pad "8" smd rect
			(at -0.75057 -1.1684 270)
			(size 0.3048 1.524)
			(layers "F.Cu" "F.Mask" "F.Paste")
			(net "P3V3_STBY")
		)
	)
	(footprint ""
		(layer "F.Cu")
		(at 97.1677 -148.108924 180)
		(property "Reference" "R29"
			(at 0 0 180)
			(layer "F.SilkS")
			(hide yes)
			(effects
				(font
					(size 1.27 1.27)
				)
			)
		)
		(property "Value" "4K7R2F-GP"
			(at 0.064008 -3.993896 180)
			(unlocked yes)
			(layer "F.Fab")
			(hide yes)
			(effects
				(font
					(size 1.016 1.016)
					(thickness 0.1524)
				)
			)
		)
		(property "Device Type" "R402H16"
			(at 0.064008 -5.517896 180)
			(unlocked yes)
			(layer "F.Fab")
			(hide yes)
			(effects
				(font
					(size 1.016 1.016)
					(thickness 0.1524)
				)
			)
		)
		(duplicate_pad_numbers_are_jumpers no)
		(fp_line
			(start 0.508 -0.9398)
			(end -0.508 -0.9398)
			(stroke
				(width 0.1524)
				(type default)
			)
			(layer "F.SilkS")
		)
		(fp_line
			(start -0.508 -0.9398)
			(end -0.508 0.9398)
			(stroke
				(width 0.1524)
				(type default)
			)
			(layer "F.SilkS")
		)
		(fp_rect
			(start -0.508 0.9398)
			(end 0.508 -0.9398)
			(stroke
				(width 0)
				(type default)
			)
			(fill no)
			(layer "F.CrtYd")
		)
		(fp_rect
			(start -0.508 0.9398)
			(end 0.508 -0.9398)
			(stroke
				(width 0)
				(type default)
			)
			(fill no)
			(layer "F.Fab")
		)
		(pad "1" smd custom
			(at 0 -0.4445 180)
			(size 0.1397 0.1397)
			(layers "F.Cu" "F.Mask" "F.Paste")
			(net "P3V3_STBY")
			(options
				(clearance outline)
				(anchor circle)
			)
			(primitives
				(gr_poly
					(pts
						(arc
							(start -0.1778 -0.2794)
							(mid -0.249642 -0.249642)
							(end -0.2794 -0.1778)
						)
						(arc
							(start -0.2794 0.1778)
							(mid -0.249642 0.249642)
							(end -0.1778 0.2794)
						)
						(arc
							(start 0.1778 0.2794)
							(mid 0.249642 0.249642)
							(end 0.2794 0.1778)
						)
						(arc
							(start 0.2794 -0.1778)
							(mid 0.249642 -0.249642)
							(end 0.1778 -0.2794)
						)
					)
					(width 0)
					(fill yes)
				)
			)
		)
		(pad "2" smd custom
			(at 0 0.4445 180)
			(size 0.1397 0.1397)
			(layers "F.Cu" "F.Mask" "F.Paste")
			(net "USB_OCS_N2")
			(options
				(clearance outline)
				(anchor circle)
			)
			(primitives
				(gr_poly
					(pts
						(arc
							(start -0.1778 -0.2794)
							(mid -0.249642 -0.249642)
							(end -0.2794 -0.1778)
						)
						(arc
							(start -0.2794 0.1778)
							(mid -0.249642 0.249642)
							(end -0.1778 0.2794)
						)
						(arc
							(start 0.1778 0.2794)
							(mid 0.249642 0.249642)
							(end 0.2794 0.1778)
						)
						(arc
							(start 0.2794 -0.1778)
							(mid 0.249642 -0.249642)
							(end 0.1778 -0.2794)
						)
					)
					(width 0)
					(fill yes)
				)
			)
		)
	)
	(footprint ""
		(layer "F.Cu")
		(at 73.4822 -156.718 -90)
		(property "Reference" "R305"
			(at 0 0 270)
			(layer "F.SilkS")
			(hide yes)
			(effects
				(font
					(size 1.27 1.27)
				)
			)
		)
		(property "Value" "10KR2F-2-GP"
			(at 0.064008 -3.993896 270)
			(unlocked yes)
			(layer "F.Fab")
			(hide yes)
			(effects
				(font
					(size 1.016 1.016)
					(thickness 0.1524)
				)
			)
		)
		(property "Device Type" "R402H16"
			(at 0.064008 -5.517896 270)
			(unlocked yes)
			(layer "F.Fab")
			(hide yes)
			(effects
				(font
					(size 1.016 1.016)
					(thickness 0.1524)
				)
			)
		)
		(duplicate_pad_numbers_are_jumpers no)
		(fp_line
			(start -0.508 -0.9398)
			(end -0.508 0.9398)
			(stroke
				(width 0.1524)
				(type default)
			)
			(layer "F.SilkS")
		)
		(fp_line
			(start 0.508 -0.9398)
			(end -0.508 -0.9398)
			(stroke
				(width 0.1524)
				(type default)
			)
			(layer "F.SilkS")
		)
		(fp_rect
			(start -0.508 0.9398)
			(end 0.508 -0.9398)
			(stroke
				(width 0)
				(type default)
			)
			(fill no)
			(layer "F.CrtYd")
		)
		(fp_rect
			(start -0.508 0.9398)
			(end 0.508 -0.9398)
			(stroke
				(width 0)
				(type default)
			)
			(fill no)
			(layer "F.Fab")
		)
		(pad "1" smd custom
			(at 0 -0.4445 270)
			(size 0.1397 0.1397)
			(layers "F.Cu" "F.Mask" "F.Paste")
			(net "P3V3_STBY")
			(options
				(clearance outline)
				(anchor circle)
			)
			(primitives
				(gr_poly
					(pts
						(arc
							(start -0.1778 -0.2794)
							(mid -0.249642 -0.249642)
							(end -0.2794 -0.1778)
						)
						(arc
							(start -0.2794 0.1778)
							(mid -0.249642 0.249642)
							(end -0.1778 0.2794)
						)
						(arc
							(start 0.1778 0.2794)
							(mid 0.249642 0.249642)
							(end 0.2794 0.1778)
						)
						(arc
							(start 0.2794 -0.1778)
							(mid 0.249642 -0.249642)
							(end 0.1778 -0.2794)
						)
					)
					(width 0)
					(fill yes)
				)
			)
		)
		(pad "2" smd custom
			(at 0 0.4445 270)
			(size 0.1397 0.1397)
			(layers "F.Cu" "F.Mask" "F.Paste")
			(net "FM_OSC_50M_EN")
			(options
				(clearance outline)
				(anchor circle)
			)
			(primitives
				(gr_poly
					(pts
						(arc
							(start -0.1778 -0.2794)
							(mid -0.249642 -0.249642)
							(end -0.2794 -0.1778)
						)
						(arc
							(start -0.2794 0.1778)
							(mid -0.249642 0.249642)
							(end -0.1778 0.2794)
						)
						(arc
							(start 0.1778 0.2794)
							(mid 0.249642 0.249642)
							(end 0.2794 0.1778)
						)
						(arc
							(start 0.2794 -0.1778)
							(mid 0.249642 -0.249642)
							(end 0.1778 -0.2794)
						)
					)
					(width 0)
					(fill yes)
				)
			)
		)
	)
	(footprint ""
		(layer "F.Cu")
		(at 208.055972 -71.6788 90)
		(property "Reference" "C313"
			(at 0 0 90)
			(layer "F.SilkS")
			(hide yes)
			(effects
				(font
					(size 1.27 1.27)
				)
			)
		)
		(property "Value" "SCD01U16V1KX-GP"
			(at -2.8321 -1.7399 90)
			(unlocked yes)
			(layer "F.Fab")
			(hide yes)
			(effects
				(font
					(size 1.016 1.016)
					(thickness 0.1524)
				)
			)
		)
		(property "Device Type" "C0201H13"
			(at -2.8321 -3.2639 90)
			(unlocked yes)
			(layer "F.Fab")
			(hide yes)
			(effects
				(font
					(size 1.016 1.016)
					(thickness 0.1524)
				)
			)
		)
		(duplicate_pad_numbers_are_jumpers no)
		(fp_rect
			(start -0.2794 0.6477)
			(end 0.2794 -0.6477)
			(stroke
				(width 0)
				(type default)
			)
			(fill no)
			(layer "F.CrtYd")
		)
		(fp_rect
			(start -0.2794 0.6477)
			(end 0.2794 -0.6477)
			(stroke
				(width 0)
				(type default)
			)
			(fill no)
			(layer "F.Fab")
		)
		(pad "1" smd custom
			(at 0 -0.2794 90)
			(size 0.0762 0.0762)
			(layers "F.Cu" "F.Mask" "F.Paste")
			(net "PHY_IOC_TO_CON_A_3_DP_C")
			(options
				(clearance outline)
				(anchor circle)
			)
			(primitives
				(gr_poly
					(pts
						(arc
							(start 0.1524 -0.127)
							(mid 0.137521 -0.162921)
							(end 0.1016 -0.1778)
						)
						(arc
							(start -0.1016 -0.1778)
							(mid -0.137521 -0.162921)
							(end -0.1524 -0.127)
						)
						(arc
							(start -0.1524 0.127)
							(mid -0.137521 0.162921)
							(end -0.1016 0.1778)
						)
						(arc
							(start 0.1016 0.1778)
							(mid 0.137521 0.162921)
							(end 0.1524 0.127)
						)
					)
					(width 0)
					(fill yes)
				)
			)
		)
		(pad "2" smd custom
			(at 0 0.2794 90)
			(size 0.0762 0.0762)
			(layers "F.Cu" "F.Mask" "F.Paste")
			(net "PHY_IOC_TO_CON_A_3_DP")
			(options
				(clearance outline)
				(anchor circle)
			)
			(primitives
				(gr_poly
					(pts
						(arc
							(start 0.1524 -0.127)
							(mid 0.137521 -0.162921)
							(end 0.1016 -0.1778)
						)
						(arc
							(start -0.1016 -0.1778)
							(mid -0.137521 -0.162921)
							(end -0.1524 -0.127)
						)
						(arc
							(start -0.1524 0.127)
							(mid -0.137521 0.162921)
							(end -0.1016 0.1778)
						)
						(arc
							(start 0.1016 0.1778)
							(mid 0.137521 0.162921)
							(end 0.1524 0.127)
						)
					)
					(width 0)
					(fill yes)
				)
			)
		)
	)
	(footprint ""
		(layer "F.Cu")
		(at 61.2394 -137.5664)
		(property "Reference" "TP71"
			(at 0 0 0)
			(layer "F.SilkS")
			(hide yes)
			(effects
				(font
					(size 1.27 1.27)
				)
			)
		)
		(property "Value" "TPAD28-2-GP"
			(at -0.0127 -1.6637 0)
			(unlocked yes)
			(layer "F.Fab")
			(hide yes)
			(effects
				(font
					(size 1.016 1.016)
					(thickness 0.1524)
				)
			)
		)
		(property "Device Type" "TPAD28"
			(at -0.0127 -3.1877 0)
			(unlocked yes)
			(layer "F.Fab")
			(hide yes)
			(effects
				(font
					(size 1.016 1.016)
					(thickness 0.1524)
				)
			)
		)
		(duplicate_pad_numbers_are_jumpers no)
		(fp_poly
			(pts
				(arc
					(start 0.3556 0)
					(mid -0.3556 0)
					(end 0.3556 0)
				)
			)
			(stroke
				(width 0)
				(type default)
			)
			(fill no)
			(layer "F.CrtYd")
		)
		(fp_poly
			(pts
				(arc
					(start 0.6096 0)
					(mid -0.6096 0)
					(end 0.6096 0)
				)
			)
			(stroke
				(width 0)
				(type default)
			)
			(fill no)
			(layer "F.Fab")
		)
		(pad "1" smd circle
			(at 0 0)
			(size 0.7112 0.7112)
			(layers "F.Cu" "F.Mask" "F.Paste")
			(net "TP_BMC_GPIOI4")
		)
	)
	(footprint ""
		(layer "F.Cu")
		(at 70.7898 -168.5544 -90)
		(property "Reference" "D11"
			(at 0 0 270)
			(layer "F.SilkS")
			(hide yes)
			(effects
				(font
					(size 1.27 1.27)
				)
			)
		)
		(property "Value" "BAT54WS-7-F-GP"
			(at 0 -6.7818 270)
			(unlocked yes)
			(layer "F.Fab")
			(hide yes)
			(effects
				(font
					(size 1.016 1.016)
					(thickness 0.1524)
				)
			)
		)
		(property "Device Type" "SOD323AKH42"
			(at 0 -8.6868 270)
			(unlocked yes)
			(layer "F.Fab")
			(hide yes)
			(effects
				(font
					(size 1.016 1.016)
					(thickness 0.1524)
				)
			)
		)
		(duplicate_pad_numbers_are_jumpers no)
		(fp_line
			(start -0.889 2.159)
			(end -0.889 -1.9304)
			(stroke
				(width 0.1524)
				(type default)
			)
			(layer "F.SilkS")
		)
		(fp_line
			(start 0.889 2.159)
			(end -0.889 2.159)
			(stroke
				(width 0.1524)
				(type default)
			)
			(layer "F.SilkS")
		)
		(fp_line
			(start 0.762 2.0574)
			(end -0.762 2.0574)
			(stroke
				(width 0.508)
				(type default)
			)
			(layer "F.SilkS")
		)
		(fp_line
			(start -0.889 -1.9304)
			(end 0.889 -1.9304)
			(stroke
				(width 0.1524)
				(type default)
			)
			(layer "F.SilkS")
		)
		(fp_line
			(start 0.889 -1.9304)
			(end 0.889 2.159)
			(stroke
				(width 0.1524)
				(type default)
			)
			(layer "F.SilkS")
		)
		(fp_rect
			(start -1.016 2.3114)
			(end 1.016 -2.0066)
			(stroke
				(width 0)
				(type default)
			)
			(fill no)
			(layer "F.CrtYd")
		)
		(fp_poly
			(pts
				(xy -1.016 -2.0066) (xy 1.016 -2.0066) (xy 1.016 2.3114) (xy -1.016 2.3114)
			)
			(stroke
				(width 0)
				(type default)
			)
			(fill no)
			(layer "F.Fab")
		)
		(pad "A" smd rect
			(at 0 -1.143 270)
			(size 0.5588 1.016)
			(layers "F.Cu" "F.Mask" "F.Paste")
			(net "BMC_SELF_HW_RST")
		)
		(pad "K" smd rect
			(at 0 1.143 270)
			(size 0.5588 1.016)
			(layers "F.Cu" "F.Mask" "F.Paste")
			(net "BMC_SELF_HW_RST_D")
		)
	)
	(footprint ""
		(layer "F.Cu")
		(at 135.40232 -27.5082)
		(property "Reference" "TP3"
			(at 0 0 0)
			(layer "F.SilkS")
			(hide yes)
			(effects
				(font
					(size 1.27 1.27)
				)
			)
		)
		(property "Value" "TPAD28-2-GP"
			(at -0.0127 -1.6637 0)
			(unlocked yes)
			(layer "F.Fab")
			(hide yes)
			(effects
				(font
					(size 1.016 1.016)
					(thickness 0.1524)
				)
			)
		)
		(property "Device Type" "TPAD28"
			(at -0.0127 -3.1877 0)
			(unlocked yes)
			(layer "F.Fab")
			(hide yes)
			(effects
				(font
					(size 1.016 1.016)
					(thickness 0.1524)
				)
			)
		)
		(duplicate_pad_numbers_are_jumpers no)
		(fp_poly
			(pts
				(arc
					(start 0.3556 0)
					(mid -0.3556 0)
					(end 0.3556 0)
				)
			)
			(stroke
				(width 0)
				(type default)
			)
			(fill no)
			(layer "F.CrtYd")
		)
		(fp_poly
			(pts
				(arc
					(start 0.6096 0)
					(mid -0.6096 0)
					(end 0.6096 0)
				)
			)
			(stroke
				(width 0)
				(type default)
			)
			(fill no)
			(layer "F.Fab")
		)
		(pad "1" smd circle
			(at 0 0)
			(size 0.7112 0.7112)
			(layers "F.Cu" "F.Mask" "F.Paste")
			(net "PCIE_COMP_TO_IOM_RST_3")
		)
	)
)
